(kicad_pcb
	(version 20260206)
	(generator "pcbnew")
	(generator_version "10.0")
	(general
		(thickness 1.6)
		(legacy_teardrops no)
	)
	(paper "A4")
	(title_block
		(title "m-2 — Lightning_M.2_BRD.brd")
		(comment 1 "Lightning (Wiwynn / Facebook NVMe JBOF) / footprints 93-99 of 157")
	)
	(layers
		(0 "F.Cu" signal "TOP")
		(4 "In1.Cu" signal "L2GND")
		(6 "In2.Cu" signal "L3")
		(8 "In3.Cu" signal "L4GND")
		(10 "In4.Cu" signal "L5GND")
		(12 "In5.Cu" signal "L6")
		(14 "In6.Cu" signal "L7GND")
		(2 "B.Cu" signal "BOTTOM")
		(9 "F.Adhes" user "F.Adhesive")
		(11 "B.Adhes" user "B.Adhesive")
		(13 "F.Paste" user "Package Geometry/Pastemask Top")
		(15 "B.Paste" user "Package Geometry/Pastemask Bottom")
		(5 "F.SilkS" user "Ref Des/Silkscreen Top")
		(7 "B.SilkS" user "Ref Des/Silkscreen Bottom")
		(1 "F.Mask" user "Board Geometry/Soldermask Top")
		(3 "B.Mask" user "Board Geometry/Soldermask Bottom")
		(17 "Dwgs.User" user "User.Drawings")
		(19 "Cmts.User" user "User.Comments")
		(21 "Eco1.User" user "User.Eco1")
		(23 "Eco2.User" user "User.Eco2")
		(25 "Edge.Cuts" user "Board Geometry/Outline")
		(27 "Margin" user)
		(31 "F.CrtYd" user "Package Geometry/Place Bound Top")
		(29 "B.CrtYd" user "Package Geometry/Place Bound Bottom")
		(35 "F.Fab" user "Ref Des/Assembly Top")
		(33 "B.Fab" user "Ref Des/Assembly Bottom")
	)
	(footprint ""
		(layer "F.Cu")
		(at 59.817 -61.722 -90)
		(property "Reference" "C14"
			(at 0 0 270)
			(layer "F.SilkS")
			(hide yes)
			(effects
				(font
					(size 1.27 1.27)
				)
			)
		)
		(property "Value" "SCD1U16V2KX-3GP"
			(at 1.1811 -2.7051 270)
			(unlocked yes)
			(layer "F.Fab")
			(hide yes)
			(effects
				(font
					(size 1.016 1.016)
					(thickness 0.1524)
				)
			)
		)
		(property "Device Type" "C402H22"
			(at 1.1811 -4.2291 270)
			(unlocked yes)
			(layer "F.Fab")
			(hide yes)
			(effects
				(font
					(size 1.016 1.016)
					(thickness 0.1524)
				)
			)
		)
		(duplicate_pad_numbers_are_jumpers no)
		(fp_rect
			(start -0.4318 0.9525)
			(end 0.4318 -0.9525)
			(stroke
				(width 0)
				(type default)
			)
			(fill no)
			(layer "F.CrtYd")
		)
		(fp_rect
			(start -0.4318 0.9525)
			(end 0.4318 -0.9525)
			(stroke
				(width 0)
				(type default)
			)
			(fill no)
			(layer "F.Fab")
		)
		(pad "1" smd custom
			(at 0 -0.4445 270)
			(size 0.1524 0.1524)
			(layers "F.Cu" "F.Mask" "F.Paste")
			(net "P3V3_PWR")
			(options
				(clearance outline)
				(anchor circle)
			)
			(primitives
				(gr_poly
					(pts
						(arc
							(start 0.3048 -0.2032)
							(mid 0.275042 -0.275042)
							(end 0.2032 -0.3048)
						)
						(arc
							(start -0.2032 -0.3048)
							(mid -0.275042 -0.275042)
							(end -0.3048 -0.2032)
						)
						(arc
							(start -0.3048 0.2032)
							(mid -0.275042 0.275042)
							(end -0.2032 0.3048)
						)
						(arc
							(start 0.2032 0.3048)
							(mid 0.275042 0.275042)
							(end 0.3048 0.2032)
						)
					)
					(width 0)
					(fill yes)
				)
			)
		)
		(pad "2" smd custom
			(at 0 0.4445 270)
			(size 0.1524 0.1524)
			(layers "F.Cu" "F.Mask" "F.Paste")
			(net "GND")
			(options
				(clearance outline)
				(anchor circle)
			)
			(primitives
				(gr_poly
					(pts
						(arc
							(start 0.3048 -0.2032)
							(mid 0.275042 -0.275042)
							(end 0.2032 -0.3048)
						)
						(arc
							(start -0.2032 -0.3048)
							(mid -0.275042 -0.275042)
							(end -0.3048 -0.2032)
						)
						(arc
							(start -0.3048 0.2032)
							(mid -0.275042 0.275042)
							(end -0.2032 0.3048)
						)
						(arc
							(start 0.2032 0.3048)
							(mid 0.275042 0.275042)
							(end 0.3048 0.2032)
						)
					)
					(width 0)
					(fill yes)
				)
			)
		)
	)
	(footprint ""
		(layer "F.Cu")
		(at 25.908 -75.819 180)
		(property "Reference" "U7"
			(at 0 0 180)
			(layer "F.SilkS")
			(hide yes)
			(effects
				(font
					(size 1.27 1.27)
				)
			)
		)
		(property "Value" "TXS0102DCUR-1-GP"
			(at 0 -11.1252 180)
			(unlocked yes)
			(layer "F.Fab")
			(hide yes)
			(effects
				(font
					(size 1.016 1.016)
					(thickness 0.1524)
				)
			)
		)
		(property "Device Type" "SSOIC8-4H36"
			(at 0 -12.6492 180)
			(unlocked yes)
			(layer "F.Fab")
			(hide yes)
			(effects
				(font
					(size 1.016 1.016)
					(thickness 0.1524)
				)
			)
		)
		(duplicate_pad_numbers_are_jumpers no)
		(fp_line
			(start 1.2573 2.1844)
			(end -1.2573 2.1844)
			(stroke
				(width 0.1524)
				(type default)
			)
			(layer "F.SilkS")
		)
		(fp_line
			(start 1.2573 -2.1844)
			(end 1.2573 2.1844)
			(stroke
				(width 0.1524)
				(type default)
			)
			(layer "F.SilkS")
		)
		(fp_line
			(start -0.9017 -0.0381)
			(end -1.2065 0.2667)
			(stroke
				(width 0.1524)
				(type default)
			)
			(layer "F.SilkS")
		)
		(fp_line
			(start -1.2065 0.2667)
			(end -1.27 0.2667)
			(stroke
				(width 0.1524)
				(type default)
			)
			(layer "F.SilkS")
		)
		(fp_line
			(start -1.2192 -0.3556)
			(end -0.9017 -0.0381)
			(stroke
				(width 0.1524)
				(type default)
			)
			(layer "F.SilkS")
		)
		(fp_line
			(start -1.2573 2.1844)
			(end -1.2573 -2.1844)
			(stroke
				(width 0.1524)
				(type default)
			)
			(layer "F.SilkS")
		)
		(fp_line
			(start -1.2573 -0.3556)
			(end -1.2192 -0.3556)
			(stroke
				(width 0.1524)
				(type default)
			)
			(layer "F.SilkS")
		)
		(fp_line
			(start -1.2573 -2.1844)
			(end 1.2573 -2.1844)
			(stroke
				(width 0.1524)
				(type default)
			)
			(layer "F.SilkS")
		)
		(fp_line
			(start -1.2954 0.4572)
			(end -1.2954 2.159)
			(stroke
				(width 0.4064)
				(type default)
			)
			(layer "F.SilkS")
		)
		(fp_poly
			(pts
				(xy -1.5113 2.4384) (xy 1.5113 2.4384) (xy 1.5113 -2.4384) (xy -1.5113 -2.4384)
			)
			(stroke
				(width 0)
				(type default)
			)
			(fill no)
			(layer "F.CrtYd")
		)
		(fp_poly
			(pts
				(xy -1.5113 -2.4384) (xy 1.5113 -2.4384) (xy 1.5113 2.4384) (xy -1.5113 2.4384)
			)
			(stroke
				(width 0)
				(type default)
			)
			(fill no)
			(layer "F.Fab")
		)
		(pad "1" smd rect
			(at -0.75057 1.1684 180)
			(size 0.3048 1.524)
			(layers "F.Cu" "F.Mask" "F.Paste")
			(net "Z50_SSD_A1_SMB_CLK_LL")
		)
		(pad "2" smd rect
			(at -0.25019 1.1684 180)
			(size 0.3048 1.524)
			(layers "F.Cu" "F.Mask" "F.Paste")
			(net "GND")
		)
		(pad "3" smd rect
			(at 0.25019 1.1684 180)
			(size 0.3048 1.524)
			(layers "F.Cu" "F.Mask" "F.Paste")
			(net "P1V8_PWR")
		)
		(pad "4" smd rect
			(at 0.75057 1.1684 180)
			(size 0.3048 1.524)
			(layers "F.Cu" "F.Mask" "F.Paste")
			(net "Z50_SSD_A1_SMB_CLK_LR")
		)
		(pad "5" smd rect
			(at 0.75057 -1.1684 180)
			(size 0.3048 1.524)
			(layers "F.Cu" "F.Mask" "F.Paste")
			(net "Z50_SSD_A1_SMB_DATA_LR")
		)
		(pad "6" smd rect
			(at 0.25019 -1.1684 180)
			(size 0.3048 1.524)
			(layers "F.Cu" "F.Mask" "F.Paste")
			(net "SSD_A1_SMB_OE")
		)
		(pad "7" smd rect
			(at -0.25019 -1.1684 180)
			(size 0.3048 1.524)
			(layers "F.Cu" "F.Mask" "F.Paste")
			(net "P3V3_DPB")
		)
		(pad "8" smd rect
			(at -0.75057 -1.1684 180)
			(size 0.3048 1.524)
			(layers "F.Cu" "F.Mask" "F.Paste")
			(net "Z50_SSD_A1_SMB_DATA_LL")
		)
	)
	(footprint ""
		(layer "F.Cu")
		(at 25.146 -71.755)
		(property "Reference" "R55"
			(at 0 0 0)
			(layer "F.SilkS")
			(hide yes)
			(effects
				(font
					(size 1.27 1.27)
				)
			)
		)
		(property "Value" "33R2J-2-GP"
			(at 0.064008 -3.993896 0)
			(unlocked yes)
			(layer "F.Fab")
			(hide yes)
			(effects
				(font
					(size 1.016 1.016)
					(thickness 0.1524)
				)
			)
		)
		(property "Device Type" "R402H16"
			(at 0.064008 -5.517896 0)
			(unlocked yes)
			(layer "F.Fab")
			(hide yes)
			(effects
				(font
					(size 1.016 1.016)
					(thickness 0.1524)
				)
			)
		)
		(duplicate_pad_numbers_are_jumpers no)
		(fp_line
			(start -0.508 -0.9398)
			(end -0.508 0.9398)
			(stroke
				(width 0.1524)
				(type default)
			)
			(layer "F.SilkS")
		)
		(fp_line
			(start 0.508 -0.9398)
			(end -0.508 -0.9398)
			(stroke
				(width 0.1524)
				(type default)
			)
			(layer "F.SilkS")
		)
		(fp_rect
			(start -0.508 0.9398)
			(end 0.508 -0.9398)
			(stroke
				(width 0)
				(type default)
			)
			(fill no)
			(layer "F.CrtYd")
		)
		(fp_rect
			(start -0.508 0.9398)
			(end 0.508 -0.9398)
			(stroke
				(width 0)
				(type default)
			)
			(fill no)
			(layer "F.Fab")
		)
		(pad "1" smd custom
			(at 0 -0.4445)
			(size 0.1397 0.1397)
			(layers "F.Cu" "F.Mask" "F.Paste")
			(net "Z50_SSD_A1_SMB_DATA_LR")
			(options
				(clearance outline)
				(anchor circle)
			)
			(primitives
				(gr_poly
					(pts
						(arc
							(start -0.1778 -0.2794)
							(mid -0.249642 -0.249642)
							(end -0.2794 -0.1778)
						)
						(arc
							(start -0.2794 0.1778)
							(mid -0.249642 0.249642)
							(end -0.1778 0.2794)
						)
						(arc
							(start 0.1778 0.2794)
							(mid 0.249642 0.249642)
							(end 0.2794 0.1778)
						)
						(arc
							(start 0.2794 -0.1778)
							(mid 0.249642 -0.249642)
							(end 0.1778 -0.2794)
						)
					)
					(width 0)
					(fill yes)
				)
			)
		)
		(pad "2" smd custom
			(at 0 0.4445)
			(size 0.1397 0.1397)
			(layers "F.Cu" "F.Mask" "F.Paste")
			(net "Z50_SSD_A1_SMB_DATA")
			(options
				(clearance outline)
				(anchor circle)
			)
			(primitives
				(gr_poly
					(pts
						(arc
							(start -0.1778 -0.2794)
							(mid -0.249642 -0.249642)
							(end -0.2794 -0.1778)
						)
						(arc
							(start -0.2794 0.1778)
							(mid -0.249642 0.249642)
							(end -0.1778 0.2794)
						)
						(arc
							(start 0.1778 0.2794)
							(mid 0.249642 0.249642)
							(end 0.2794 0.1778)
						)
						(arc
							(start 0.2794 -0.1778)
							(mid 0.249642 -0.249642)
							(end 0.1778 -0.2794)
						)
					)
					(width 0)
					(fill yes)
				)
			)
		)
	)
	(footprint ""
		(layer "F.Cu")
		(at 37.338 -80.264)
		(property "Reference" "PC37"
			(at 0 0 0)
			(layer "F.SilkS")
			(hide yes)
			(effects
				(font
					(size 1.27 1.27)
				)
			)
		)
		(property "Value" "SC10U16V5KX-1-GP"
			(at -0.0762 -6.1214 0)
			(unlocked yes)
			(layer "F.Fab")
			(hide yes)
			(effects
				(font
					(size 1.016 1.016)
					(thickness 0.1524)
				)
			)
		)
		(property "Device Type" "C805H54"
			(at -0.0762 -8.1534 0)
			(unlocked yes)
			(layer "F.Fab")
			(hide yes)
			(effects
				(font
					(size 1.016 1.016)
					(thickness 0.1524)
				)
			)
		)
		(duplicate_pad_numbers_are_jumpers no)
		(fp_line
			(start 0.635 0)
			(end -0.635 0)
			(stroke
				(width 0.508)
				(type default)
			)
			(layer "F.SilkS")
		)
		(fp_rect
			(start -0.9652 1.778)
			(end 0.9652 -1.778)
			(stroke
				(width 0)
				(type default)
			)
			(fill no)
			(layer "F.CrtYd")
		)
		(fp_poly
			(pts
				(xy -0.9652 -1.778) (xy 0.9652 -1.778) (xy 0.9652 1.778) (xy -0.9652 1.778)
			)
			(stroke
				(width 0)
				(type default)
			)
			(fill no)
			(layer "F.Fab")
		)
		(pad "1" smd rect
			(at 0 -0.9652)
			(size 1.397 1.143)
			(layers "F.Cu" "F.Mask" "F.Paste")
			(net "P3V3_DEV_VIN")
		)
		(pad "2" smd rect
			(at 0 0.9652)
			(size 1.397 1.143)
			(layers "F.Cu" "F.Mask" "F.Paste")
			(net "GND")
		)
	)
	(footprint ""
		(layer "B.Cu")
		(at 23.495 -77.216)
		(property "Reference" "R61"
			(at 0 0 0)
			(layer "B.SilkS")
			(hide yes)
			(effects
				(font
					(size 1.27 1.27)
				)
				(justify mirror)
			)
		)
		(property "Value" "0R2J-2-GP"
			(at -0.064008 -3.993896 0)
			(unlocked yes)
			(layer "B.Fab")
			(hide yes)
			(effects
				(font
					(size 1.016 1.016)
					(thickness 0.1524)
				)
				(justify mirror)
			)
		)
		(property "Device Type" "R402H16"
			(at -0.064008 -5.517896 0)
			(unlocked yes)
			(layer "B.Fab")
			(hide yes)
			(effects
				(font
					(size 1.016 1.016)
					(thickness 0.1524)
				)
				(justify mirror)
			)
		)
		(duplicate_pad_numbers_are_jumpers no)
		(fp_line
			(start -0.508 -0.9398)
			(end 0.508 -0.9398)
			(stroke
				(width 0.1524)
				(type default)
			)
			(layer "B.SilkS")
		)
		(fp_line
			(start 0.508 -0.9398)
			(end 0.508 0.9398)
			(stroke
				(width 0.1524)
				(type default)
			)
			(layer "B.SilkS")
		)
		(fp_rect
			(start 0.508 0.9398)
			(end -0.508 -0.9398)
			(stroke
				(width 0)
				(type default)
			)
			(fill no)
			(layer "B.CrtYd")
		)
		(fp_rect
			(start 0.508 0.9398)
			(end -0.508 -0.9398)
			(stroke
				(width 0)
				(type default)
			)
			(fill no)
			(layer "B.Fab")
		)
		(pad "1" smd custom
			(at 0 -0.4445 180)
			(size 0.1397 0.1397)
			(layers "B.Cu" "B.Mask" "B.Paste")
			(net "Z50_SSD_A1_SMB_DATA_R")
			(options
				(clearance outline)
				(anchor circle)
			)
			(primitives
				(gr_poly
					(pts
						(arc
							(start -0.1778 0.2794)
							(mid -0.249642 0.249642)
							(end -0.2794 0.1778)
						)
						(arc
							(start -0.2794 -0.1778)
							(mid -0.249642 -0.249642)
							(end -0.1778 -0.2794)
						)
						(arc
							(start 0.1778 -0.2794)
							(mid 0.249642 -0.249642)
							(end 0.2794 -0.1778)
						)
						(arc
							(start 0.2794 0.1778)
							(mid 0.249642 0.249642)
							(end 0.1778 0.2794)
						)
					)
					(width 0)
					(fill yes)
				)
			)
		)
		(pad "2" smd custom
			(at 0 0.4445 180)
			(size 0.1397 0.1397)
			(layers "B.Cu" "B.Mask" "B.Paste")
			(net "Z50_SSD_A1_SMB_DATA")
			(options
				(clearance outline)
				(anchor circle)
			)
			(primitives
				(gr_poly
					(pts
						(arc
							(start -0.1778 0.2794)
							(mid -0.249642 0.249642)
							(end -0.2794 0.1778)
						)
						(arc
							(start -0.2794 -0.1778)
							(mid -0.249642 -0.249642)
							(end -0.1778 -0.2794)
						)
						(arc
							(start 0.1778 -0.2794)
							(mid 0.249642 -0.249642)
							(end 0.2794 -0.1778)
						)
						(arc
							(start 0.2794 0.1778)
							(mid 0.249642 0.249642)
							(end 0.1778 0.2794)
						)
					)
					(width 0)
					(fill yes)
				)
			)
		)
	)
	(footprint ""
		(layer "B.Cu")
		(at 59.260994 -40.259)
		(property "Reference" "R7"
			(at 0 0 0)
			(layer "B.SilkS")
			(hide yes)
			(effects
				(font
					(size 1.27 1.27)
				)
				(justify mirror)
			)
		)
		(property "Value" "4K7R2F-GP"
			(at -0.064008 -3.993896 0)
			(unlocked yes)
			(layer "B.Fab")
			(hide yes)
			(effects
				(font
					(size 1.016 1.016)
					(thickness 0.1524)
				)
				(justify mirror)
			)
		)
		(property "Device Type" "R402H16"
			(at -0.064008 -5.517896 0)
			(unlocked yes)
			(layer "B.Fab")
			(hide yes)
			(effects
				(font
					(size 1.016 1.016)
					(thickness 0.1524)
				)
				(justify mirror)
			)
		)
		(duplicate_pad_numbers_are_jumpers no)
		(fp_line
			(start -0.508 -0.9398)
			(end 0.508 -0.9398)
			(stroke
				(width 0.1524)
				(type default)
			)
			(layer "B.SilkS")
		)
		(fp_line
			(start 0.508 -0.9398)
			(end 0.508 0.9398)
			(stroke
				(width 0.1524)
				(type default)
			)
			(layer "B.SilkS")
		)
		(fp_rect
			(start 0.508 0.9398)
			(end -0.508 -0.9398)
			(stroke
				(width 0)
				(type default)
			)
			(fill no)
			(layer "B.CrtYd")
		)
		(fp_rect
			(start 0.508 0.9398)
			(end -0.508 -0.9398)
			(stroke
				(width 0)
				(type default)
			)
			(fill no)
			(layer "B.Fab")
		)
		(pad "1" smd custom
			(at 0 -0.4445 180)
			(size 0.1397 0.1397)
			(layers "B.Cu" "B.Mask" "B.Paste")
			(net "P3V3_DPB")
			(options
				(clearance outline)
				(anchor circle)
			)
			(primitives
				(gr_poly
					(pts
						(arc
							(start -0.1778 0.2794)
							(mid -0.249642 0.249642)
							(end -0.2794 0.1778)
						)
						(arc
							(start -0.2794 -0.1778)
							(mid -0.249642 -0.249642)
							(end -0.1778 -0.2794)
						)
						(arc
							(start 0.1778 -0.2794)
							(mid 0.249642 -0.249642)
							(end 0.2794 -0.1778)
						)
						(arc
							(start 0.2794 0.1778)
							(mid 0.249642 0.249642)
							(end 0.1778 0.2794)
						)
					)
					(width 0)
					(fill yes)
				)
			)
		)
		(pad "2" smd custom
			(at 0 0.4445 180)
			(size 0.1397 0.1397)
			(layers "B.Cu" "B.Mask" "B.Paste")
			(net "Z50_TEMP_1_A1")
			(options
				(clearance outline)
				(anchor circle)
			)
			(primitives
				(gr_poly
					(pts
						(arc
							(start -0.1778 0.2794)
							(mid -0.249642 0.249642)
							(end -0.2794 0.1778)
						)
						(arc
							(start -0.2794 -0.1778)
							(mid -0.249642 -0.249642)
							(end -0.1778 -0.2794)
						)
						(arc
							(start 0.1778 -0.2794)
							(mid 0.249642 -0.249642)
							(end 0.2794 -0.1778)
						)
						(arc
							(start 0.2794 0.1778)
							(mid 0.249642 0.249642)
							(end 0.1778 0.2794)
						)
					)
					(width 0)
					(fill yes)
				)
			)
		)
	)
	(footprint ""
		(layer "B.Cu")
		(at 58.244994 -40.259 180)
		(property "Reference" "R11"
			(at 0 0 0)
			(layer "B.SilkS")
			(hide yes)
			(effects
				(font
					(size 1.27 1.27)
				)
				(justify mirror)
			)
		)
		(property "Value" "4K7R2F-GP"
			(at -0.064008 -3.993896 180)
			(unlocked yes)
			(layer "B.Fab")
			(hide yes)
			(effects
				(font
					(size 1.016 1.016)
					(thickness 0.1524)
				)
				(justify mirror)
			)
		)
		(property "Device Type" "R402H16"
			(at -0.064008 -5.517896 180)
			(unlocked yes)
			(layer "B.Fab")
			(hide yes)
			(effects
				(font
					(size 1.016 1.016)
					(thickness 0.1524)
				)
				(justify mirror)
			)
		)
		(duplicate_pad_numbers_are_jumpers no)
		(fp_line
			(start 0.508 -0.9398)
			(end 0.508 0.9398)
			(stroke
				(width 0.1524)
				(type default)
			)
			(layer "B.SilkS")
		)
		(fp_line
			(start -0.508 -0.9398)
			(end 0.508 -0.9398)
			(stroke
				(width 0.1524)
				(type default)
			)
			(layer "B.SilkS")
		)
		(fp_rect
			(start 0.508 0.9398)
			(end -0.508 -0.9398)
			(stroke
				(width 0)
				(type default)
			)
			(fill no)
			(layer "B.CrtYd")
		)
		(fp_rect
			(start 0.508 0.9398)
			(end -0.508 -0.9398)
			(stroke
				(width 0)
				(type default)
			)
			(fill no)
			(layer "B.Fab")
		)
		(pad "1" smd custom
			(at 0 -0.4445)
			(size 0.1397 0.1397)
			(layers "B.Cu" "B.Mask" "B.Paste")
			(net "Z50_TEMP_1_A1")
			(options
				(clearance outline)
				(anchor circle)
			)
			(primitives
				(gr_poly
					(pts
						(arc
							(start -0.1778 0.2794)
							(mid -0.249642 0.249642)
							(end -0.2794 0.1778)
						)
						(arc
							(start -0.2794 -0.1778)
							(mid -0.249642 -0.249642)
							(end -0.1778 -0.2794)
						)
						(arc
							(start 0.1778 -0.2794)
							(mid 0.249642 -0.249642)
							(end 0.2794 -0.1778)
						)
						(arc
							(start 0.2794 0.1778)
							(mid 0.249642 0.249642)
							(end 0.1778 0.2794)
						)
					)
					(width 0)
					(fill yes)
				)
			)
		)
		(pad "2" smd custom
			(at 0 0.4445)
			(size 0.1397 0.1397)
			(layers "B.Cu" "B.Mask" "B.Paste")
			(net "GND")
			(options
				(clearance outline)
				(anchor circle)
			)
			(primitives
				(gr_poly
					(pts
						(arc
							(start -0.1778 0.2794)
							(mid -0.249642 0.249642)
							(end -0.2794 0.1778)
						)
						(arc
							(start -0.2794 -0.1778)
							(mid -0.249642 -0.249642)
							(end -0.1778 -0.2794)
						)
						(arc
							(start 0.1778 -0.2794)
							(mid 0.249642 -0.249642)
							(end 0.2794 -0.1778)
						)
						(arc
							(start 0.2794 0.1778)
							(mid 0.249642 0.249642)
							(end 0.1778 0.2794)
						)
					)
					(width 0)
					(fill yes)
				)
			)
		)
	)
)
